(kicad_pcb
	(version 20260206)
	(generator "pcbnew")
	(generator_version "10.0")
	(general
		(thickness 1.6)
		(legacy_teardrops no)
	)
	(paper "A4")
	(title_block
		(title "01162023_DA0F0TEBIF0_F0T_Expander_BD_F_brd_V02_OCP.brd")
		(comment 1 "Grand Teton / footprints 5666-5672 of 9728")
	)
	(layers
		(0 "F.Cu" signal "TOP")
		(4 "In1.Cu" signal "GND")
		(6 "In2.Cu" signal "VCC")
		(8 "In3.Cu" signal "VCC1")
		(10 "In4.Cu" signal "GND1")
		(12 "In5.Cu" signal "IN1")
		(14 "In6.Cu" signal "GND2")
		(16 "In7.Cu" signal "IN2")
		(18 "In8.Cu" signal "GND3")
		(20 "In9.Cu" signal "IN3")
		(22 "In10.Cu" signal "GND4")
		(24 "In11.Cu" signal "IN4")
		(26 "In12.Cu" signal "GND5")
		(28 "In13.Cu" signal "IN5")
		(30 "In14.Cu" signal "GND6")
		(32 "In15.Cu" signal "IN6")
		(34 "In16.Cu" signal "GND7")
		(2 "B.Cu" signal "BOTTOM")
		(9 "F.Adhes" user "F.Adhesive")
		(11 "B.Adhes" user "B.Adhesive")
		(13 "F.Paste" user "Package Geometry/Pastemask Top")
		(15 "B.Paste" user "Package Geometry/Pastemask Bottom")
		(5 "F.SilkS" user "Ref Des/Silkscreen Top")
		(7 "B.SilkS" user "Ref Des/Silkscreen Bottom")
		(1 "F.Mask" user "Board Geometry/Soldermask Top")
		(3 "B.Mask" user "Board Geometry/Soldermask Bottom")
		(17 "Dwgs.User" user "User.Drawings")
		(19 "Cmts.User" user "User.Comments")
		(21 "Eco1.User" user "User.Eco1")
		(23 "Eco2.User" user "User.Eco2")
		(25 "Edge.Cuts" user "Board Geometry/Outline")
		(27 "Margin" user)
		(31 "F.CrtYd" user "Package Geometry/Place Bound Top")
		(29 "B.CrtYd" user "Package Geometry/Place Bound Bottom")
		(35 "F.Fab" user "Ref Des/Assembly Top")
		(33 "B.Fab" user "Ref Des/Assembly Bottom")
	)
	(footprint ""
		(layer "F.Cu")
		(at 258.46786 -53.051456)
		(property "Reference" "R4466"
			(at 0 0 0)
			(layer "F.SilkS")
			(hide yes)
			(effects
				(font
					(size 1.27 1.27)
				)
			)
		)
		(property "Value" ""
			(at 0 0 0)
			(layer "F.Fab")
			(effects
				(font
					(size 1.27 1.27)
				)
			)
		)
		(duplicate_pad_numbers_are_jumpers no)
		(fp_line
			(start -0.7874 -0.4064)
			(end 0.7874 -0.4064)
			(stroke
				(width 0.1524)
				(type default)
			)
			(layer "F.SilkS")
		)
		(fp_line
			(start -0.7874 0.4064)
			(end -0.7874 -0.4064)
			(stroke
				(width 0.1524)
				(type default)
			)
			(layer "F.SilkS")
		)
		(fp_line
			(start 0.7874 -0.4064)
			(end 0.7874 0.4064)
			(stroke
				(width 0.1524)
				(type default)
			)
			(layer "F.SilkS")
		)
		(fp_line
			(start 0.7874 0.4064)
			(end -0.7874 0.4064)
			(stroke
				(width 0.1524)
				(type default)
			)
			(layer "F.SilkS")
		)
		(fp_line
			(start -0.67945 -0.305054)
			(end -0.12065 -0.305054)
			(stroke
				(width 0.1)
				(type default)
			)
			(layer "F.Fab")
		)
		(fp_line
			(start -0.67945 0.3048)
			(end -0.67945 -0.305054)
			(stroke
				(width 0.1)
				(type default)
			)
			(layer "F.Fab")
		)
		(fp_line
			(start -0.12065 -0.305054)
			(end -0.12065 -0.2794)
			(stroke
				(width 0.1)
				(type default)
			)
			(layer "F.Fab")
		)
		(fp_line
			(start -0.12065 -0.2794)
			(end 0.12065 -0.2794)
			(stroke
				(width 0.1)
				(type default)
			)
			(layer "F.Fab")
		)
		(fp_line
			(start -0.12065 0.2794)
			(end -0.12065 0.3048)
			(stroke
				(width 0.1)
				(type default)
			)
			(layer "F.Fab")
		)
		(fp_line
			(start -0.12065 0.3048)
			(end -0.67945 0.3048)
			(stroke
				(width 0.1)
				(type default)
			)
			(layer "F.Fab")
		)
		(fp_line
			(start 0.120396 0.2794)
			(end -0.12065 0.2794)
			(stroke
				(width 0.1)
				(type default)
			)
			(layer "F.Fab")
		)
		(fp_line
			(start 0.120396 0.3048)
			(end 0.120396 0.2794)
			(stroke
				(width 0.1)
				(type default)
			)
			(layer "F.Fab")
		)
		(fp_line
			(start 0.12065 -0.3048)
			(end 0.67945 -0.3048)
			(stroke
				(width 0.1)
				(type default)
			)
			(layer "F.Fab")
		)
		(fp_line
			(start 0.12065 -0.2794)
			(end 0.12065 -0.3048)
			(stroke
				(width 0.1)
				(type default)
			)
			(layer "F.Fab")
		)
		(fp_line
			(start 0.67945 -0.3048)
			(end 0.67945 0.3048)
			(stroke
				(width 0.1)
				(type default)
			)
			(layer "F.Fab")
		)
		(fp_line
			(start 0.67945 0.3048)
			(end 0.120396 0.3048)
			(stroke
				(width 0.1)
				(type default)
			)
			(layer "F.Fab")
		)
		(pad "1" smd circle
			(at -0.40005 0)
			(size 0 0)
			(layers "F.Cu" "F.Mask" "F.Paste")
			(net "PWRGD_P12V_SSD8")
		)
		(pad "2" smd circle
			(at 0.40005 0)
			(size 0 0)
			(layers "F.Cu" "F.Mask" "F.Paste")
			(net "PWRGD_P12V_SSD8_R")
		)
	)
	(footprint ""
		(layer "F.Cu")
		(at 142.368016 -53.051456)
		(property "Reference" "R4459"
			(at 0 0 0)
			(layer "F.SilkS")
			(hide yes)
			(effects
				(font
					(size 1.27 1.27)
				)
			)
		)
		(property "Value" ""
			(at 0 0 0)
			(layer "F.Fab")
			(effects
				(font
					(size 1.27 1.27)
				)
			)
		)
		(duplicate_pad_numbers_are_jumpers no)
		(fp_line
			(start -0.7874 -0.4064)
			(end 0.7874 -0.4064)
			(stroke
				(width 0.1524)
				(type default)
			)
			(layer "F.SilkS")
		)
		(fp_line
			(start -0.7874 0.4064)
			(end -0.7874 -0.4064)
			(stroke
				(width 0.1524)
				(type default)
			)
			(layer "F.SilkS")
		)
		(fp_line
			(start 0.7874 -0.4064)
			(end 0.7874 0.4064)
			(stroke
				(width 0.1524)
				(type default)
			)
			(layer "F.SilkS")
		)
		(fp_line
			(start 0.7874 0.4064)
			(end -0.7874 0.4064)
			(stroke
				(width 0.1524)
				(type default)
			)
			(layer "F.SilkS")
		)
		(fp_line
			(start -0.67945 -0.305054)
			(end -0.12065 -0.305054)
			(stroke
				(width 0.1)
				(type default)
			)
			(layer "F.Fab")
		)
		(fp_line
			(start -0.67945 0.3048)
			(end -0.67945 -0.305054)
			(stroke
				(width 0.1)
				(type default)
			)
			(layer "F.Fab")
		)
		(fp_line
			(start -0.12065 -0.305054)
			(end -0.12065 -0.2794)
			(stroke
				(width 0.1)
				(type default)
			)
			(layer "F.Fab")
		)
		(fp_line
			(start -0.12065 -0.2794)
			(end 0.12065 -0.2794)
			(stroke
				(width 0.1)
				(type default)
			)
			(layer "F.Fab")
		)
		(fp_line
			(start -0.12065 0.2794)
			(end -0.12065 0.3048)
			(stroke
				(width 0.1)
				(type default)
			)
			(layer "F.Fab")
		)
		(fp_line
			(start -0.12065 0.3048)
			(end -0.67945 0.3048)
			(stroke
				(width 0.1)
				(type default)
			)
			(layer "F.Fab")
		)
		(fp_line
			(start 0.120396 0.2794)
			(end -0.12065 0.2794)
			(stroke
				(width 0.1)
				(type default)
			)
			(layer "F.Fab")
		)
		(fp_line
			(start 0.120396 0.3048)
			(end 0.120396 0.2794)
			(stroke
				(width 0.1)
				(type default)
			)
			(layer "F.Fab")
		)
		(fp_line
			(start 0.12065 -0.3048)
			(end 0.67945 -0.3048)
			(stroke
				(width 0.1)
				(type default)
			)
			(layer "F.Fab")
		)
		(fp_line
			(start 0.12065 -0.2794)
			(end 0.12065 -0.3048)
			(stroke
				(width 0.1)
				(type default)
			)
			(layer "F.Fab")
		)
		(fp_line
			(start 0.67945 -0.3048)
			(end 0.67945 0.3048)
			(stroke
				(width 0.1)
				(type default)
			)
			(layer "F.Fab")
		)
		(fp_line
			(start 0.67945 0.3048)
			(end 0.120396 0.3048)
			(stroke
				(width 0.1)
				(type default)
			)
			(layer "F.Fab")
		)
		(pad "1" smd circle
			(at -0.40005 0)
			(size 0 0)
			(layers "F.Cu" "F.Mask" "F.Paste")
			(net "PWRGD_P12V_SSD4")
		)
		(pad "2" smd circle
			(at 0.40005 0)
			(size 0 0)
			(layers "F.Cu" "F.Mask" "F.Paste")
			(net "PWRGD_P12V_SSD4_R")
		)
	)
	(footprint ""
		(layer "F.Cu")
		(at 78.267814 -52.035456 180)
		(property "Reference" "R865"
			(at 0 0 180)
			(layer "F.SilkS")
			(hide yes)
			(effects
				(font
					(size 1.27 1.27)
				)
			)
		)
		(property "Value" ""
			(at 0 0 180)
			(layer "F.Fab")
			(effects
				(font
					(size 1.27 1.27)
				)
			)
		)
		(duplicate_pad_numbers_are_jumpers no)
		(fp_line
			(start 0.7874 0.4064)
			(end -0.7874 0.4064)
			(stroke
				(width 0.1524)
				(type default)
			)
			(layer "F.SilkS")
		)
		(fp_line
			(start 0.7874 -0.4064)
			(end 0.7874 0.4064)
			(stroke
				(width 0.1524)
				(type default)
			)
			(layer "F.SilkS")
		)
		(fp_line
			(start -0.7874 0.4064)
			(end -0.7874 -0.4064)
			(stroke
				(width 0.1524)
				(type default)
			)
			(layer "F.SilkS")
		)
		(fp_line
			(start -0.7874 -0.4064)
			(end 0.7874 -0.4064)
			(stroke
				(width 0.1524)
				(type default)
			)
			(layer "F.SilkS")
		)
		(fp_line
			(start 0.67945 0.3048)
			(end 0.120396 0.3048)
			(stroke
				(width 0.1)
				(type default)
			)
			(layer "F.Fab")
		)
		(fp_line
			(start 0.67945 -0.3048)
			(end 0.67945 0.3048)
			(stroke
				(width 0.1)
				(type default)
			)
			(layer "F.Fab")
		)
		(fp_line
			(start 0.12065 -0.2794)
			(end 0.12065 -0.3048)
			(stroke
				(width 0.1)
				(type default)
			)
			(layer "F.Fab")
		)
		(fp_line
			(start 0.12065 -0.3048)
			(end 0.67945 -0.3048)
			(stroke
				(width 0.1)
				(type default)
			)
			(layer "F.Fab")
		)
		(fp_line
			(start 0.120396 0.3048)
			(end 0.120396 0.2794)
			(stroke
				(width 0.1)
				(type default)
			)
			(layer "F.Fab")
		)
		(fp_line
			(start 0.120396 0.2794)
			(end -0.12065 0.2794)
			(stroke
				(width 0.1)
				(type default)
			)
			(layer "F.Fab")
		)
		(fp_line
			(start -0.12065 0.3048)
			(end -0.67945 0.3048)
			(stroke
				(width 0.1)
				(type default)
			)
			(layer "F.Fab")
		)
		(fp_line
			(start -0.12065 0.2794)
			(end -0.12065 0.3048)
			(stroke
				(width 0.1)
				(type default)
			)
			(layer "F.Fab")
		)
		(fp_line
			(start -0.12065 -0.2794)
			(end 0.12065 -0.2794)
			(stroke
				(width 0.1)
				(type default)
			)
			(layer "F.Fab")
		)
		(fp_line
			(start -0.12065 -0.305054)
			(end -0.12065 -0.2794)
			(stroke
				(width 0.1)
				(type default)
			)
			(layer "F.Fab")
		)
		(fp_line
			(start -0.67945 0.3048)
			(end -0.67945 -0.305054)
			(stroke
				(width 0.1)
				(type default)
			)
			(layer "F.Fab")
		)
		(fp_line
			(start -0.67945 -0.305054)
			(end -0.12065 -0.305054)
			(stroke
				(width 0.1)
				(type default)
			)
			(layer "F.Fab")
		)
		(pad "1" smd circle
			(at -0.40005 0 180)
			(size 0 0)
			(layers "F.Cu" "F.Mask" "F.Paste")
			(net "P3V3_AUX")
		)
		(pad "2" smd circle
			(at 0.40005 0 180)
			(size 0 0)
			(layers "F.Cu" "F.Mask" "F.Paste")
			(net "PWRGD_P12V_SSD2")
		)
	)
	(footprint ""
		(layer "F.Cu")
		(at 148.809202 -27.04973 180)
		(property "Reference" "C2768"
			(at 0 0 180)
			(layer "F.SilkS")
			(hide yes)
			(effects
				(font
					(size 1.27 1.27)
				)
			)
		)
		(property "Value" ""
			(at 0 0 180)
			(layer "F.Fab")
			(effects
				(font
					(size 1.27 1.27)
				)
			)
		)
		(duplicate_pad_numbers_are_jumpers no)
		(fp_line
			(start 0.7874 0.4064)
			(end -0.7874 0.4064)
			(stroke
				(width 0.1524)
				(type default)
			)
			(layer "F.SilkS")
		)
		(fp_line
			(start 0.7874 -0.4064)
			(end 0.7874 0.4064)
			(stroke
				(width 0.1524)
				(type default)
			)
			(layer "F.SilkS")
		)
		(fp_line
			(start -0.7874 0.4064)
			(end -0.7874 -0.4064)
			(stroke
				(width 0.1524)
				(type default)
			)
			(layer "F.SilkS")
		)
		(fp_line
			(start -0.7874 -0.4064)
			(end 0.7874 -0.4064)
			(stroke
				(width 0.1524)
				(type default)
			)
			(layer "F.SilkS")
		)
		(fp_line
			(start 0.67945 0.3048)
			(end 0.120396 0.3048)
			(stroke
				(width 0.1)
				(type default)
			)
			(layer "F.Fab")
		)
		(fp_line
			(start 0.67945 -0.3048)
			(end 0.67945 0.3048)
			(stroke
				(width 0.1)
				(type default)
			)
			(layer "F.Fab")
		)
		(fp_line
			(start 0.12065 -0.2794)
			(end 0.12065 -0.3048)
			(stroke
				(width 0.1)
				(type default)
			)
			(layer "F.Fab")
		)
		(fp_line
			(start 0.12065 -0.3048)
			(end 0.67945 -0.3048)
			(stroke
				(width 0.1)
				(type default)
			)
			(layer "F.Fab")
		)
		(fp_line
			(start 0.120396 0.3048)
			(end 0.120396 0.2794)
			(stroke
				(width 0.1)
				(type default)
			)
			(layer "F.Fab")
		)
		(fp_line
			(start 0.120396 0.2794)
			(end -0.12065 0.2794)
			(stroke
				(width 0.1)
				(type default)
			)
			(layer "F.Fab")
		)
		(fp_line
			(start -0.12065 0.3048)
			(end -0.67945 0.3048)
			(stroke
				(width 0.1)
				(type default)
			)
			(layer "F.Fab")
		)
		(fp_line
			(start -0.12065 0.2794)
			(end -0.12065 0.3048)
			(stroke
				(width 0.1)
				(type default)
			)
			(layer "F.Fab")
		)
		(fp_line
			(start -0.12065 -0.2794)
			(end 0.12065 -0.2794)
			(stroke
				(width 0.1)
				(type default)
			)
			(layer "F.Fab")
		)
		(fp_line
			(start -0.12065 -0.305054)
			(end -0.12065 -0.2794)
			(stroke
				(width 0.1)
				(type default)
			)
			(layer "F.Fab")
		)
		(fp_line
			(start -0.67945 0.3048)
			(end -0.67945 -0.305054)
			(stroke
				(width 0.1)
				(type default)
			)
			(layer "F.Fab")
		)
		(fp_line
			(start -0.67945 -0.305054)
			(end -0.12065 -0.305054)
			(stroke
				(width 0.1)
				(type default)
			)
			(layer "F.Fab")
		)
		(pad "1" smd circle
			(at -0.40005 0 180)
			(size 0 0)
			(layers "F.Cu" "F.Mask" "F.Paste")
			(net "PRSNT_SSD5_R_N")
		)
		(pad "2" smd circle
			(at 0.40005 0 180)
			(size 0 0)
			(layers "F.Cu" "F.Mask" "F.Paste")
			(net "GND")
		)
	)
	(footprint ""
		(layer "F.Cu")
		(at 196.119242 -123.184666 180)
		(property "Reference" "C238"
			(at 0 0 180)
			(layer "F.SilkS")
			(hide yes)
			(effects
				(font
					(size 1.27 1.27)
				)
			)
		)
		(property "Value" ""
			(at 0 0 180)
			(layer "F.Fab")
			(effects
				(font
					(size 1.27 1.27)
				)
			)
		)
		(duplicate_pad_numbers_are_jumpers no)
		(fp_line
			(start 0.299974 0.150114)
			(end -0.299974 0.150114)
			(stroke
				(width 0.1)
				(type default)
			)
			(layer "F.Fab")
		)
		(fp_line
			(start 0.299974 -0.150114)
			(end 0.299974 0.150114)
			(stroke
				(width 0.1)
				(type default)
			)
			(layer "F.Fab")
		)
		(fp_line
			(start -0.299974 0.150114)
			(end -0.299974 -0.150114)
			(stroke
				(width 0.1)
				(type default)
			)
			(layer "F.Fab")
		)
		(fp_line
			(start -0.299974 -0.150114)
			(end 0.299974 -0.150114)
			(stroke
				(width 0.1)
				(type default)
			)
			(layer "F.Fab")
		)
		(pad "1" smd rect
			(at -0.2667 0 180)
			(size 0.3048 0.381)
			(layers "F.Cu" "F.Mask" "F.Paste")
			(net "P5E_PEX1_STN0_TX_DP<2>")
		)
		(pad "2" smd rect
			(at 0.2667 0 180)
			(size 0.3048 0.381)
			(layers "F.Cu" "F.Mask" "F.Paste")
			(net "P5E_PEX1_STN0_TX_C_DP<2>")
		)
	)
	(footprint ""
		(layer "F.Cu")
		(at 372.07698 -343.952322 90)
		(property "Reference" "C763"
			(at 0 0 90)
			(layer "F.SilkS")
			(hide yes)
			(effects
				(font
					(size 1.27 1.27)
				)
			)
		)
		(property "Value" ""
			(at 0 0 90)
			(layer "F.Fab")
			(effects
				(font
					(size 1.27 1.27)
				)
			)
		)
		(duplicate_pad_numbers_are_jumpers no)
		(fp_line
			(start 0.299974 -0.150114)
			(end 0.299974 0.150114)
			(stroke
				(width 0.1)
				(type default)
			)
			(layer "F.Fab")
		)
		(fp_line
			(start -0.299974 -0.150114)
			(end 0.299974 -0.150114)
			(stroke
				(width 0.1)
				(type default)
			)
			(layer "F.Fab")
		)
		(fp_line
			(start 0.299974 0.150114)
			(end -0.299974 0.150114)
			(stroke
				(width 0.1)
				(type default)
			)
			(layer "F.Fab")
		)
		(fp_line
			(start -0.299974 0.150114)
			(end -0.299974 -0.150114)
			(stroke
				(width 0.1)
				(type default)
			)
			(layer "F.Fab")
		)
		(pad "1" smd rect
			(at -0.2667 0 90)
			(size 0.3048 0.381)
			(layers "F.Cu" "F.Mask" "F.Paste")
			(net "P5E_PEX3_STN6_TX_DN<111>")
		)
		(pad "2" smd rect
			(at 0.2667 0 90)
			(size 0.3048 0.381)
			(layers "F.Cu" "F.Mask" "F.Paste")
			(net "P5E_PEX3_STN6_TX_C_DN<111>")
		)
	)
	(footprint ""
		(layer "F.Cu")
		(at 154.707844 -160.380934)
		(property "Reference" "R125"
			(at 0 0 0)
			(layer "F.SilkS")
			(hide yes)
			(effects
				(font
					(size 1.27 1.27)
				)
			)
		)
		(property "Value" ""
			(at 0 0 0)
			(layer "F.Fab")
			(effects
				(font
					(size 1.27 1.27)
				)
			)
		)
		(duplicate_pad_numbers_are_jumpers no)
		(fp_line
			(start -0.7874 -0.4064)
			(end 0.7874 -0.4064)
			(stroke
				(width 0.1524)
				(type default)
			)
			(layer "F.SilkS")
		)
		(fp_line
			(start -0.7874 0.4064)
			(end -0.7874 -0.4064)
			(stroke
				(width 0.1524)
				(type default)
			)
			(layer "F.SilkS")
		)
		(fp_line
			(start 0.7874 -0.4064)
			(end 0.7874 0.4064)
			(stroke
				(width 0.1524)
				(type default)
			)
			(layer "F.SilkS")
		)
		(fp_line
			(start 0.7874 0.4064)
			(end -0.7874 0.4064)
			(stroke
				(width 0.1524)
				(type default)
			)
			(layer "F.SilkS")
		)
		(fp_line
			(start -0.67945 -0.305054)
			(end -0.12065 -0.305054)
			(stroke
				(width 0.1)
				(type default)
			)
			(layer "F.Fab")
		)
		(fp_line
			(start -0.67945 0.3048)
			(end -0.67945 -0.305054)
			(stroke
				(width 0.1)
				(type default)
			)
			(layer "F.Fab")
		)
		(fp_line
			(start -0.12065 -0.305054)
			(end -0.12065 -0.2794)
			(stroke
				(width 0.1)
				(type default)
			)
			(layer "F.Fab")
		)
		(fp_line
			(start -0.12065 -0.2794)
			(end 0.12065 -0.2794)
			(stroke
				(width 0.1)
				(type default)
			)
			(layer "F.Fab")
		)
		(fp_line
			(start -0.12065 0.2794)
			(end -0.12065 0.3048)
			(stroke
				(width 0.1)
				(type default)
			)
			(layer "F.Fab")
		)
		(fp_line
			(start -0.12065 0.3048)
			(end -0.67945 0.3048)
			(stroke
				(width 0.1)
				(type default)
			)
			(layer "F.Fab")
		)
		(fp_line
			(start 0.120396 0.2794)
			(end -0.12065 0.2794)
			(stroke
				(width 0.1)
				(type default)
			)
			(layer "F.Fab")
		)
		(fp_line
			(start 0.120396 0.3048)
			(end 0.120396 0.2794)
			(stroke
				(width 0.1)
				(type default)
			)
			(layer "F.Fab")
		)
		(fp_line
			(start 0.12065 -0.3048)
			(end 0.67945 -0.3048)
			(stroke
				(width 0.1)
				(type default)
			)
			(layer "F.Fab")
		)
		(fp_line
			(start 0.12065 -0.2794)
			(end 0.12065 -0.3048)
			(stroke
				(width 0.1)
				(type default)
			)
			(layer "F.Fab")
		)
		(fp_line
			(start 0.67945 -0.3048)
			(end 0.67945 0.3048)
			(stroke
				(width 0.1)
				(type default)
			)
			(layer "F.Fab")
		)
		(fp_line
			(start 0.67945 0.3048)
			(end 0.120396 0.3048)
			(stroke
				(width 0.1)
				(type default)
			)
			(layer "F.Fab")
		)
		(pad "1" smd circle
			(at -0.40005 0)
			(size 0 0)
			(layers "F.Cu" "F.Mask" "F.Paste")
			(net "NIC2_MAIN_PWR_EN")
		)
		(pad "2" smd circle
			(at 0.40005 0)
			(size 0 0)
			(layers "F.Cu" "F.Mask" "F.Paste")
			(net "GND")
		)
	)
)
